# TIMECARD (Time Appliance Project (Time Card)) — schematic netlist excerpt (pin names and nets, part order shuffled) for the footprints in the layout excerpt that follows; sources: Cadence DE-HDL packaged netlist, KiCad conversion of R4006-B0001-02_R01.brd

C300  CAPACITOR  10UF 25V 20%  pkg SMC_0805R_H057  page 33 : \1\ = UNNAMED_525_CAPACITOR_I16_1 ; \2\ = SG
TP14  TP_PIONT  pkg TP010CT020B030_PTH  page 25 : \1\ = MUX1_SEL
C274  CAPACITOR  10UF 6.3V 20%  pkg SMC_0402R_H022  page 18 : \1\ = VDD3V3_SHT31A ; \2\ = SG

(kicad_pcb
	(version 20260206)
	(generator "pcbnew")
	(generator_version "10.0")
	(general
		(thickness 1.6)
		(legacy_teardrops no)
	)
	(paper "A4")
	(title_block
		(title "timecard-production-celestica-r4006 — R4006-B0001-02_R01.brd")
		(comment 1 "Time Appliance Project (Time Card) / footprints 91-93 of 1113")
	)
	(layers
		(0 "F.Cu" signal "TOP")
		(4 "In1.Cu" signal "L02_GND1")
		(6 "In2.Cu" signal "L03_SIG1")
		(8 "In3.Cu" signal "L04_GND2")
		(10 "In4.Cu" signal "L05_VCC1")
		(12 "In5.Cu" signal "L06_VCC2")
		(14 "In6.Cu" signal "L07_GND3")
		(16 "In7.Cu" signal "L08_SIG2")
		(18 "In8.Cu" signal "L09_GND4")
		(2 "B.Cu" signal "BOTTOM")
		(9 "F.Adhes" user "F.Adhesive")
		(11 "B.Adhes" user "B.Adhesive")
		(13 "F.Paste" user "Package Geometry/Pastemask Top")
		(15 "B.Paste" user "Package Geometry/Pastemask Bottom")
		(5 "F.SilkS" user "Ref Des/Silkscreen Top")
		(7 "B.SilkS" user "Ref Des/Silkscreen Bottom")
		(1 "F.Mask" user "Board Geometry/Soldermask Top")
		(3 "B.Mask" user "Board Geometry/Soldermask Bottom")
		(17 "Dwgs.User" user "User.Drawings")
		(19 "Cmts.User" user "User.Comments")
		(21 "Eco1.User" user "User.Eco1")
		(23 "Eco2.User" user "User.Eco2")
		(25 "Edge.Cuts" user "Board Geometry/Outline")
		(27 "Margin" user)
		(31 "F.CrtYd" user "Package Geometry/Place Bound Top")
		(29 "B.CrtYd" user "Package Geometry/Place Bound Bottom")
		(35 "F.Fab" user "Ref Des/Assembly Top")
		(33 "B.Fab" user "Ref Des/Assembly Bottom")
	)
	(footprint ""
		(layer "F.Cu")
		(at 47.117 -78.867)
		(property "Reference" "C300"
			(at 3.175 0.03937 0)
			(unlocked yes)
			(layer "F.SilkS")
			(effects
				(font
					(size 0.7874 0.5842)
					(thickness 0.1524)
				)
			)
		)
		(property "Value" "VAL*"
			(at 0.0762 3.134106 0)
			(unlocked yes)
			(layer "F.Fab")
			(hide yes)
			(effects
				(font
					(size 0.7874 0.5842)
					(thickness 0.1524)
				)
			)
		)
		(property "Tolerance" "TOL*"
			(at 0.0762 4.048506 0)
			(unlocked yes)
			(layer "Cmts.User")
			(hide yes)
			(effects
				(font
					(size 0.7874 0.5842)
					(thickness 0.1524)
				)
			)
		)
		(property "User Part Number" "PARTNUM*"
			(at 0.1016 5.013706 0)
			(unlocked yes)
			(layer "Cmts.User")
			(hide yes)
			(effects
				(font
					(size 0.7874 0.5842)
					(thickness 0.1524)
				)
			)
		)
		(property "Device Type" "CAPACITOR-G107-0F106-EM,10UF,2A"
			(at 0.0508 2.194306 0)
			(unlocked yes)
			(layer "F.Fab")
			(hide yes)
			(effects
				(font
					(size 0.7874 0.5842)
					(thickness 0.1524)
				)
			)
		)
		(duplicate_pad_numbers_are_jumpers no)
		(fp_line
			(start -1.5748 -0.9398)
			(end -1.5748 0.9398)
			(stroke
				(width 0.1)
				(type default)
			)
			(layer "F.SilkS")
		)
		(fp_line
			(start -1.5748 0.9398)
			(end 1.5748 0.9398)
			(stroke
				(width 0.1)
				(type default)
			)
			(layer "F.SilkS")
		)
		(fp_line
			(start 1.5748 -0.9398)
			(end -1.5748 -0.9398)
			(stroke
				(width 0.1)
				(type default)
			)
			(layer "F.SilkS")
		)
		(fp_line
			(start 1.5748 0.9398)
			(end 1.5748 -0.9398)
			(stroke
				(width 0.1)
				(type default)
			)
			(layer "F.SilkS")
		)
		(fp_rect
			(start -1.5748 0.9398)
			(end 1.5748 -0.9398)
			(stroke
				(width 0)
				(type default)
			)
			(fill no)
			(layer "F.CrtYd")
		)
		(fp_line
			(start -1.016 -0.635)
			(end -1.016 0.635)
			(stroke
				(width 0.1)
				(type default)
			)
			(layer "F.Fab")
		)
		(fp_line
			(start -1.016 0.635)
			(end 1.016 0.635)
			(stroke
				(width 0.1)
				(type default)
			)
			(layer "F.Fab")
		)
		(fp_line
			(start 1.016 -0.635)
			(end -1.016 -0.635)
			(stroke
				(width 0.1)
				(type default)
			)
			(layer "F.Fab")
		)
		(fp_line
			(start 1.016 0.635)
			(end 1.016 -0.635)
			(stroke
				(width 0.1)
				(type default)
			)
			(layer "F.Fab")
		)
		(pad "1" smd rect
			(at -0.8382 0)
			(size 0.9652 1.3716)
			(layers "F.Cu" "F.Mask" "F.Paste")
			(net "UNNAMED_525_CAPACITOR_I16_1")
		)
		(pad "2" smd rect
			(at 0.8382 0)
			(size 0.9652 1.3716)
			(layers "F.Cu" "F.Mask" "F.Paste")
			(net "SG")
		)
		(zone
			(layer "F.Cu")
			(hatch none 0.5)
			(connect_pads
				(clearance 0)
			)
			(min_thickness 0.25)
			(keepout
				(tracks not_allowed)
				(vias allowed)
				(pads allowed)
				(copperpour not_allowed)
				(footprints allowed)
			)
			(placement
				(enabled no)
				(sheetname "")
			)
			(fill
				(thermal_gap 0.5)
				(thermal_bridge_width 0.5)
				(island_removal_mode 0)
			)
			(polygon
				(pts
					(xy 46.8884 -78.232) (xy 47.3456 -78.232) (xy 47.3456 -79.502) (xy 46.8884 -79.502)
				)
			)
		)
		(zone
			(layer "F.Cu")
			(hatch none 0.5)
			(connect_pads
				(clearance 0)
			)
			(min_thickness 0.25)
			(keepout
				(tracks allowed)
				(vias not_allowed)
				(pads allowed)
				(copperpour not_allowed)
				(footprints allowed)
			)
			(placement
				(enabled no)
				(sheetname "")
			)
			(fill
				(thermal_gap 0.5)
				(thermal_bridge_width 0.5)
				(island_removal_mode 0)
			)
			(polygon
				(pts
					(xy 46.8884 -78.232) (xy 47.3456 -78.232) (xy 47.3456 -79.502) (xy 46.8884 -79.502)
				)
			)
		)
	)
	(footprint ""
		(layer "F.Cu")
		(at 153.67 -56.515)
		(property "Reference" "C274"
			(at 1.905 2.19837 0)
			(unlocked yes)
			(layer "F.SilkS")
			(effects
				(font
					(size 0.7874 0.5842)
					(thickness 0.1524)
				)
			)
		)
		(property "Value" "VAL*"
			(at 0.0762 2.067306 0)
			(unlocked yes)
			(layer "F.Fab")
			(hide yes)
			(effects
				(font
					(size 0.7874 0.5842)
					(thickness 0.1524)
				)
			)
		)
		(property "Device Type" "CAPACITOR-G105-0C106-BM,10UF,2A"
			(at 0.0508 1.127506 0)
			(unlocked yes)
			(layer "F.Fab")
			(hide yes)
			(effects
				(font
					(size 0.7874 0.5842)
					(thickness 0.1524)
				)
			)
		)
		(property "User Part Number" "PARTNUM*"
			(at 0.1016 4.023106 0)
			(unlocked yes)
			(layer "Cmts.User")
			(hide yes)
			(effects
				(font
					(size 0.7874 0.5842)
					(thickness 0.1524)
				)
			)
		)
		(property "Tolerance" "TOL*"
			(at 0.0762 3.032506 0)
			(unlocked yes)
			(layer "Cmts.User")
			(hide yes)
			(effects
				(font
					(size 0.7874 0.5842)
					(thickness 0.1524)
				)
			)
		)
		(duplicate_pad_numbers_are_jumpers no)
		(fp_line
			(start -1.143 -0.5588)
			(end -1.143 0.5588)
			(stroke
				(width 0.1)
				(type default)
			)
			(layer "F.SilkS")
		)
		(fp_line
			(start -1.143 0.5588)
			(end 1.143 0.5588)
			(stroke
				(width 0.1)
				(type default)
			)
			(layer "F.SilkS")
		)
		(fp_line
			(start 1.143 -0.5588)
			(end -1.143 -0.5588)
			(stroke
				(width 0.1)
				(type default)
			)
			(layer "F.SilkS")
		)
		(fp_line
			(start 1.143 0.5588)
			(end 1.143 -0.5588)
			(stroke
				(width 0.1)
				(type default)
			)
			(layer "F.SilkS")
		)
		(fp_rect
			(start 1.143 -0.5588)
			(end -1.143 0.5588)
			(stroke
				(width 0)
				(type default)
			)
			(fill no)
			(layer "F.CrtYd")
		)
		(fp_line
			(start -0.508 -0.3048)
			(end -0.508 0.3048)
			(stroke
				(width 0.1)
				(type default)
			)
			(layer "F.Fab")
		)
		(fp_line
			(start -0.508 0.3048)
			(end 0.508 0.3048)
			(stroke
				(width 0.1)
				(type default)
			)
			(layer "F.Fab")
		)
		(fp_line
			(start 0.508 -0.3048)
			(end -0.508 -0.3048)
			(stroke
				(width 0.1)
				(type default)
			)
			(layer "F.Fab")
		)
		(fp_line
			(start 0.508 0.3048)
			(end 0.508 -0.3048)
			(stroke
				(width 0.1)
				(type default)
			)
			(layer "F.Fab")
		)
		(pad "1" smd rect
			(at -0.5334 0)
			(size 0.7112 0.6096)
			(layers "F.Cu" "F.Mask" "F.Paste")
			(net "VDD3V3_SHT31A")
		)
		(pad "2" smd rect
			(at 0.5334 0)
			(size 0.7112 0.6096)
			(layers "F.Cu" "F.Mask" "F.Paste")
			(net "SG")
		)
		(zone
			(layer "F.Cu")
			(hatch none 0.5)
			(connect_pads
				(clearance 0)
			)
			(min_thickness 0.25)
			(keepout
				(tracks allowed)
				(vias not_allowed)
				(pads allowed)
				(copperpour not_allowed)
				(footprints allowed)
			)
			(placement
				(enabled no)
				(sheetname "")
			)
			(fill
				(thermal_gap 0.5)
				(thermal_bridge_width 0.5)
				(island_removal_mode 0)
			)
			(polygon
				(pts
					(xy 153.7462 -56.8198) (xy 153.5938 -56.8198) (xy 153.5938 -56.2102) (xy 153.7462 -56.2102)
				)
			)
		)
	)
	(footprint ""
		(layer "F.Cu")
		(at 100.33 -97.028)
		(property "Reference" "TP14"
			(at -1.0414 -1.36525 0)
			(unlocked yes)
			(layer "F.SilkS")
			(effects
				(font
					(size 0.635 0.4064)
					(thickness 0.1524)
				)
				(justify left)
			)
		)
		(property "Value" ""
			(at 0 0 0)
			(layer "F.Fab")
			(effects
				(font
					(size 1.27 1.27)
				)
			)
		)
		(property "Device Type" "TP_PIONT-TP010CT020B030_PTH-TPA"
			(at -1.341882 0.996696 0)
			(unlocked yes)
			(layer "F.Fab")
			(hide yes)
			(effects
				(font
					(size 0.7874 0.5842)
					(thickness 0.000001)
				)
				(justify left)
			)
		)
		(duplicate_pad_numbers_are_jumpers no)
		(fp_poly
			(pts
				(arc
					(start 0.889 0)
					(mid -0.889 0)
					(end 0.889 0)
				)
			)
			(stroke
				(width 0)
				(type default)
			)
			(fill no)
			(layer "B.CrtYd")
		)
		(fp_poly
			(pts
				(arc
					(start 0.889 0)
					(mid -0.889 0)
					(end 0.889 0)
				)
			)
			(stroke
				(width 0)
				(type default)
			)
			(fill no)
			(layer "F.CrtYd")
		)
		(pad "1" thru_hole circle
			(at 0 0)
			(size 0.508 0.508)
			(drill 0.254)
			(layers "*.Cu" "*.Mask")
			(remove_unused_layers no)
			(net "MUX1_SEL")
			(clearance 0.1016)
			(padstack
				(mode front_inner_back)
				(layer "Inner"
					(shape circle)
					(size 0.508 0.508)
					(clearance 0.1016)
				)
				(layer "B.Cu"
					(shape circle)
					(size 0.762 0.762)
					(clearance -0.0254)
				)
			)
		)
	)
)
